FILE_TYPE = MACRO_DRAWING;
SET COLOR_WIRE YELLOW;
SET COLOR_PROP ORANGE;
SET COLOR_DOT WHITE;
SET COLOR_ARC YELLOW;
SET COLOR_BODY GREEN;
SET COLOR_NOTE PURPLE;
SET PROP_DISPLAY VALUE;
SET PAGE_NUMBER P18;
FORCEADD TABLE_TOC_CL..1
(3200 -350);
FORCEPROP 2 LAST CUSTOM_TXT_CDS <XR_PAGE_TITLE>
J 0
(-4170 5350);
DISPLAY 0.638298 (-4170 5350);
PAINT PINK (-4170 5350);
FORCEPROP 1 LAST CUSTOM_TXT_CDS <TITLE>
J 1
(1315 255);
DISPLAY 0.978723 (1315 255);
FORCEPROP 1 LAST CUSTOM_TXT_CDS <DOCREV>
J 0
(2475 25);
DISPLAY 0.978723 (2475 25);
FORCEPROP 1 LAST CUSTOM_TXT_CDS <DATE>
J 0
(2475 -175);
DISPLAY 0.978723 (2475 -175);
FORCEPROP 1 LAST CUSTOM_TXT_CDS <CON_PAGE_NUM>
J 0
(1020 -300);
DISPLAY 0.978723 (1020 -300);
FORCEPROP 1 LAST CUSTOM_TXT_CDS <CON_TOTAL_PAGES>
J 0
(1350 -300);
DISPLAY 0.978723 (1350 -300);
FORCEPROP 1 LAST CUSTOM_TXT_CDS <DESIGNER>
J 0
(2475 225);
DISPLAY 0.978723 (2475 225);
FORCEPROP 1 LAST CUSTOM_TXT_CDS <DOCNO>
J 0
(1250 35);
DISPLAY 0.978723 (1250 35);
FORCEPROP 1 LAST CUSTOM_TXT_CDS <ASSY_PN>
J 0
(1250 -175);
DISPLAY 0.978723 (1250 -175);
FORCEPROP 1 LAST PAGEREV_2 PAGE/REV
J 0
(-350 4275);
DISPLAY 1.510638 (-350 4275);
PAINT GREEN (-350 4275);
FORCEPROP 1 LAST PAGEREV_1 PAGE/REV
J 0
(-3650 4275);
DISPLAY 1.510638 (-3650 4275);
PAINT GREEN (-3650 4275);
FORCEPROP 1 LAST TITLE CHANGE_LIST
J 0
(-1300 4700);
DISPLAY 2.957447 (-1300 4700);
PAINT GREEN (-1300 4700);
FORCEPROP 2 LAST CDS_LIB cls
J 0
(3200 -350);
DISPLAY INVISIBLE (3200 -350);
FORCEPROP 1 LAST CDS_LMAN_SYM_OUTLINE -7700,5800,200,-200
J 0
(3200 -350);
DISPLAY 0.468085 (3200 -350);
PAINT GREEN (3200 -350);
DISPLAY INVISIBLE (3200 -350);
FORCEPROP 2 LAST CDS_XR_PAGE_TITLE CR-35 : @TIMECARD_LIB.TIMECARD(SCH_1):PAGE35
J 0
(-4170 5350);
DISPLAY 0.638298 (-4170 5350);
PAINT PINK (-4170 5350);
DISPLAY INVISIBLE (-4170 5350);
FORCEPROP 2 LAST PAGE_BORDER TRUE
J 0
(-4170 5350);
DISPLAY 0.638298 (-4170 5350);
PAINT PINK (-4170 5350);
DISPLAY INVISIBLE (-4170 5350);
FORCEPROP 1 LAST COMMENT_BODY TRUE
J 0
(3210 -295);
DISPLAY 0.808511 (3210 -295);
DISPLAY INVISIBLE (3210 -295);
FORCENOTE
- CTH-MFG REQ, CHANGE REFDES FOR CPN:G380-10013-01= SP42-SP71. THIS CHANGE WILL NOT AFFECT THE PCB LAYOUT.
(-2900 2100) 0;
DISPLAY LEFT (-2900 2100);
DISPLAY 0.404255 (-2900 2100);
FORCENOTE
- CTH-MFG REQ, CHANGE REFDES FOR CPN:G380-10015-01= SP1-SP41. THIS CHANGE WILL NOT AFFECT THE PCB LAYOUT.
(-2900 2150) 0;
DISPLAY LEFT (-2900 2150);
DISPLAY 0.404255 (-2900 2150);
FORCENOTE
- CTH-MFG REQ, CHANGE Q'TY FOR CPN G380-10015-01 FROM 63 PCS TO 41 PCS, CPN G380-10013-01 FROM 62 PCS TO 30 PCS.
(-2900 2250) 0;
DISPLAY LEFT (-2900 2250);
DISPLAY 0.404255 (-2900 2250);
FORCENOTE
- R450 = ASSY, R451 = NO_ASSY, R402= 2K2.
(-2900 2300) 0;
DISPLAY LEFT (-2900 2300);
DISPLAY 0.404255 (-2900 2300);
FORCENOTE
- SCHEMATIC RELEASE FOR PCBA CPN:R4006-G0001-03 REV03.
(-2900 2400) 0;
DISPLAY LEFT (-2900 2400);
DISPLAY 0.510638 (-2900 2400);
FORCENOTE
- SCHEMATIC RELEASE DATE: SEP 02, 2022. 
(-2900 2450) 0;
DISPLAY LEFT (-2900 2450);
DISPLAY 0.510638 (-2900 2450);
FORCENOTE
- THE FLASHROM TOOL (FTDI<>SPI FLASH) DOES NOT SUPPORT YET FOR THE SPI FLASH CPN:G221-10224-01 MPN:MT25QL128ABA1ESE-0SIT.
(-2900 2750) 0;
DISPLAY LEFT (-2900 2750);
DISPLAY 0.404255 (-2900 2750);
FORCENOTE
- THE LOGICAL LIBRARY FOR CPN:G229-10017-01 HAS NOT CREATED YET FOR THE CONCEPT HDL CAD 
(-2900 3200) 0;
DISPLAY LEFT (-2900 3200);
DISPLAY 0.510638 (-2900 3200);
FORCENOTE
- THUS, MANUALLY CHANGE U34 FROM G222-00082-01 TO G229-10017-01 FOR THE BOM FILE.
(-2900 3150) 0;
DISPLAY LEFT (-2900 3150);
DISPLAY 0.510638 (-2900 3150);
FORCENOTE
REV 1.0 [DVT]
(-3650 3450) 0;
DISPLAY LEFT (-3650 3450);
DISPLAY 0.510638 (-3650 3450);
FORCENOTE
- SCHEMATIC RELEASE FOR ASSY_CPN:R4006-G00001-01.
(-2900 3900) 0;
DISPLAY LEFT (-2900 3900);
DISPLAY 0.510638 (-2900 3900);
FORCENOTE
- SCHEMATIC RELEASE DATE: OCT 14, 2021.
(-2900 3950) 0;
DISPLAY LEFT (-2900 3950);
DISPLAY 0.510638 (-2900 3950);
FORCENOTE
- SCHEMATIC RELEASE FOR THE PCB CPN: R4006-B0001-01_R01.PCB RELEASE DATE: OCT 12, 2021.
(-2900 4050) 0;
DISPLAY LEFT (-2900 4050);
DISPLAY 0.510638 (-2900 4050);
FORCENOTE
R4006-G0001-01-SC
(-3650 4100) 0;
DISPLAY LEFT (-3650 4100);
DISPLAY 0.638298 (-3650 4100);
FORCENOTE
- SCHEMATIC RELEASE DATE: OCT 20, 2021.
(-2900 3800) 0;
DISPLAY LEFT (-2900 3800);
DISPLAY 0.510638 (-2900 3800);
FORCENOTE
- SCHEMATIC RELEASE DATE: OCT 12, 2021.
(-2900 4100) 0;
DISPLAY LEFT (-2900 4100);
DISPLAY 0.510638 (-2900 4100);
FORCENOTE
REV 1.0 [EVT]
(-3650 4050) 0;
DISPLAY LEFT (-3650 4050);
DISPLAY 0.510638 (-3650 4050);
FORCENOTE
REV 2.0 [DVT]
(-3650 3300) 0;
DISPLAY LEFT (-3650 3300);
DISPLAY 0.510638 (-3650 3300);
FORCENOTE
REV 1.0 [PVT]
(-3650 2850) 0;
DISPLAY LEFT (-3650 2850);
DISPLAY 0.510638 (-3650 2850);
FORCENOTE
REV 2.0 [MP]
(-3650 2400) 0;
DISPLAY LEFT (-3650 2400);
DISPLAY 0.510638 (-3650 2400);
FORCENOTE
R4006-G0001-03-SC
(-3650 2900) 0;
DISPLAY LEFT (-3650 2900);
DISPLAY 0.638298 (-3650 2900);
FORCENOTE
R4006-G0001-02-SC
(-3650 3350) 0;
DISPLAY LEFT (-3650 3350);
DISPLAY 0.638298 (-3650 3350);
FORCENOTE
R4006-G0001-02-SC
(-3650 3500) 0;
DISPLAY LEFT (-3650 3500);
DISPLAY 0.638298 (-3650 3500);
FORCENOTE
R4006-G0001-03-SC
(-3650 2450) 0;
DISPLAY LEFT (-3650 2450);
DISPLAY 0.638298 (-3650 2450);
FORCENOTE
REV 2.0 [EVT]
(-3650 3750) 0;
DISPLAY LEFT (-3650 3750);
DISPLAY 0.510638 (-3650 3750);
FORCENOTE
- CHANGED R186 FROM CPN:G155-03241-01 TO CPN:G155-03001-01. R189 = NO_ASSY.
(-2900 3750) 0;
DISPLAY LEFT (-2900 3750);
DISPLAY 0.510638 (-2900 3750);
FORCENOTE
- SCHEMATIC RELEASE DATE: FEB 25, 2022.
(-2900 3500) 0;
DISPLAY LEFT (-2900 3500);
DISPLAY 0.510638 (-2900 3500);
FORCENOTE
R4006-G0001-01-SC
(-3650 3800) 0;
DISPLAY LEFT (-3650 3800);
DISPLAY 0.638298 (-3650 3800);
FORCENOTE
- SCHEMATIC RELEASE FOR THE PCB CPN: R4006-B0001-02.PCB RELEASE DATE: FEB 25,2022.
(-2900 3450) 0;
DISPLAY LEFT (-2900 3450);
DISPLAY 0.510638 (-2900 3450);
FORCENOTE
- SCHEMATIC RELEASE DATE: MAR 10, 2022. SCHEMATIC RELEASE FOR PCBA CPN:R4006-G0001-02 REV03.
(-2900 3350) 0;
DISPLAY LEFT (-2900 3350);
DISPLAY 0.510638 (-2900 3350);
FORCENOTE
- PART SHORTAGE, CHANGED CPN:G222-00082-01"TPS3808G33" TO CPN:G229-10017-01"TPS3808G30".
(-2900 3300) 0;
DISPLAY LEFT (-2900 3300);
DISPLAY 0.510638 (-2900 3300);
FORCENOTE
- SCHEMATIC RELEASE FOR PCBA CPN:R4006-G0001-03 REV01.
(-2900 2850) 0;
DISPLAY LEFT (-2900 2850);
DISPLAY 0.510638 (-2900 2850);
FORCENOTE
- THUS, MANUALLY CHANGE U23 FROM G221-10224-01 TO G221-10359-01 FOR THE BOM FILE.
(-2900 2700) 0;
DISPLAY LEFT (-2900 2700);
DISPLAY 0.404255 (-2900 2700);
FORCENOTE
- SCHEMATIC RELEASE DATE: JUL 05, 2022. 
(-2900 2900) 0;
DISPLAY LEFT (-2900 2900);
DISPLAY 0.510638 (-2900 2900);
QUIT
